(kicad_pcb
	(version 20241229)
	(generator "pcbnew")
	(generator_version "9.0")
	(general
		(thickness 1.61)
		(legacy_teardrops no)
	)
	(paper "A3")
	(title_block
		(title "RDIMM DDR5 Tester")
		(date "2026-05-21")
		(rev "2.2.0")
		(company "Antmicro")
		(comment 9 "footprints 66-70 of 796")
	)
	(layers
		(0 "F.Cu" signal)
		(4 "In1.Cu" power)
		(6 "In2.Cu" mixed)
		(8 "In3.Cu" power)
		(10 "In4.Cu" mixed)
		(12 "In5.Cu" power)
		(14 "In6.Cu" mixed)
		(16 "In7.Cu" power)
		(18 "In8.Cu" power)
		(20 "In9.Cu" mixed)
		(22 "In10.Cu" power)
		(2 "B.Cu" signal)
		(9 "F.Adhes" user "F.Adhesive")
		(11 "B.Adhes" user "B.Adhesive")
		(13 "F.Paste" user)
		(15 "B.Paste" user)
		(5 "F.SilkS" user "F.Silkscreen")
		(7 "B.SilkS" user "B.Silkscreen")
		(1 "F.Mask" user)
		(3 "B.Mask" user)
		(17 "Dwgs.User" user "User.Drawings")
		(19 "Cmts.User" user "User.Comments")
		(21 "Eco1.User" user "User.Eco1")
		(23 "Eco2.User" user "User.Eco2")
		(25 "Edge.Cuts" user)
		(27 "Margin" user)
		(31 "F.CrtYd" user "F.Courtyard")
		(29 "B.CrtYd" user "B.Courtyard")
		(35 "F.Fab" user)
		(33 "B.Fab" user)
	)
	(footprint "antmicro-footprints:C_0603_1608Metric"
		(layer "F.Cu")
		(at 248.793 153.921 90)
		(descr "Capacitor SMD 0603")
		(tags "capacitor 0603")
		(property "Reference" "C191"
			(at -1.104 -0.993 90)
			(layer "F.SilkS")
			(effects
				(font
					(size 0.7 0.7)
					(thickness 0.15)
				)
				(justify left bottom)
			)
		)
		(property "Value" "C_22u_0603"
			(at -1.42757 1.770288 90)
			(layer "F.Fab")
			(effects
				(font
					(size 0.7 0.7)
					(thickness 0.15)
				)
				(justify left bottom)
			)
		)
		(property "Datasheet" "https://www.murata.com/products/productdetail?partno=GRM188R60J226MEA0%23"
			(at 0 0 90)
			(layer "F.Fab")
			(hide yes)
			(effects
				(font
					(size 1.27 1.27)
					(thickness 0.15)
				)
			)
		)
		(property "Manufacturer" "Murata"
			(at 0 0 90)
			(unlocked yes)
			(layer "F.Fab")
			(hide yes)
			(effects
				(font
					(size 1 1)
					(thickness 0.15)
				)
			)
		)
		(property "MPN" "GRM188R60J226MEA0D"
			(at 0 0 90)
			(unlocked yes)
			(layer "F.Fab")
			(hide yes)
			(effects
				(font
					(size 1 1)
					(thickness 0.15)
				)
			)
		)
		(property "Val" "22u"
			(at 0 0 90)
			(unlocked yes)
			(layer "F.Fab")
			(hide yes)
			(effects
				(font
					(size 1 1)
					(thickness 0.15)
				)
			)
		)
		(property "License" "Apache-2.0"
			(at 0 0 90)
			(unlocked yes)
			(layer "F.Fab")
			(hide yes)
			(effects
				(font
					(size 1 1)
					(thickness 0.15)
				)
			)
		)
		(property "Author" "Antmicro"
			(at 0 0 90)
			(unlocked yes)
			(layer "F.Fab")
			(hide yes)
			(effects
				(font
					(size 1 1)
					(thickness 0.15)
				)
			)
		)
		(property "Voltage" ""
			(at 0 0 90)
			(unlocked yes)
			(layer "F.Fab")
			(hide yes)
			(effects
				(font
					(size 1 1)
					(thickness 0.15)
				)
			)
		)
		(property "Dielectric" ""
			(at 0 0 90)
			(unlocked yes)
			(layer "F.Fab")
			(hide yes)
			(effects
				(font
					(size 1 1)
					(thickness 0.15)
				)
			)
		)
		(sheetname "/Supply/DC-DC IO/")
		(sheetfile "dc-dc-io.kicad_sch")
		(attr smd)
		(fp_line
			(start -0.15 -0.4)
			(end 0.15 -0.4)
			(stroke
				(width 0.15)
				(type solid)
			)
			(layer "F.SilkS")
		)
		(fp_line
			(start -0.15 0.4)
			(end 0.15 0.4)
			(stroke
				(width 0.15)
				(type solid)
			)
			(layer "F.SilkS")
		)
		(fp_rect
			(start -1.25 -0.65)
			(end 1.25 0.65)
			(stroke
				(width 0.05)
				(type solid)
			)
			(fill no)
			(layer "F.CrtYd")
		)
		(fp_rect
			(start -0.8 -0.4)
			(end 0.8 0.4)
			(stroke
				(width 0.15)
				(type solid)
			)
			(fill no)
			(layer "F.Fab")
		)
		(fp_text user "License: Apache-2.0"
			(at -1.682 5.895 90)
			(layer "F.Fab")
			(effects
				(font
					(size 0.7 0.7)
					(thickness 0.15)
				)
				(justify left bottom)
			)
		)
		(fp_text user "Author: Antmicro"
			(at -1.682 4.894 90)
			(layer "F.Fab")
			(effects
				(font
					(size 0.7 0.7)
					(thickness 0.15)
				)
				(justify left bottom)
			)
		)
		(fp_text user "${REFERENCE}"
			(at -1.682 3.895 90)
			(layer "F.Fab")
			(effects
				(font
					(size 0.7 0.7)
					(thickness 0.15)
				)
				(justify left bottom)
			)
		)
		(pad "1" smd roundrect
			(at -0.7 0 90)
			(size 0.8 1)
			(layers "F.Cu" "F.Mask" "F.Paste")
			(roundrect_rratio 0.2)
			(net 1 "GND")
			(pintype "passive")
		)
		(pad "2" smd roundrect
			(at 0.7 0 90)
			(size 0.8 1)
			(layers "F.Cu" "F.Mask" "F.Paste")
			(roundrect_rratio 0.2)
			(net 46 "/Supply/DC-DC IO/5V_local")
			(pintype "passive")
		)
	)
	(footprint "antmicro-footprints:C_0402_1005Metric"
		(layer "F.Cu")
		(at 164.94 161.154999 -90)
		(descr "Capacitor SMD 0402")
		(tags "capacitor SMD 0402")
		(property "Reference" "C288"
			(at -4.105 -0.43 90)
			(layer "F.SilkS")
			(effects
				(font
					(size 0.7 0.7)
					(thickness 0.15)
				)
				(justify right bottom)
			)
		)
		(property "Value" "C_10u_10V_0402"
			(at -1.022927 2.155213 90)
			(layer "F.Fab")
			(effects
				(font
					(size 0.7 0.7)
					(thickness 0.15)
				)
				(justify right bottom)
			)
		)
		(property "Datasheet" "https://www.murata.com/products/productdetail?partno=GRM155R61A106ME11%23"
			(at 0 0 270)
			(layer "F.Fab")
			(hide yes)
			(effects
				(font
					(size 1.27 1.27)
					(thickness 0.15)
				)
			)
		)
		(property "MPN" "GRM155R61A106ME11D"
			(at 0 0 270)
			(unlocked yes)
			(layer "F.Fab")
			(hide yes)
			(effects
				(font
					(size 1 1)
					(thickness 0.15)
				)
			)
		)
		(property "Manufacturer" "Murata"
			(at 0 0 270)
			(unlocked yes)
			(layer "F.Fab")
			(hide yes)
			(effects
				(font
					(size 1 1)
					(thickness 0.15)
				)
			)
		)
		(property "License" "Apache-2.0"
			(at 0 0 270)
			(unlocked yes)
			(layer "F.Fab")
			(hide yes)
			(effects
				(font
					(size 1 1)
					(thickness 0.15)
				)
			)
		)
		(property "Author" "Antmicro"
			(at 0 0 270)
			(unlocked yes)
			(layer "F.Fab")
			(hide yes)
			(effects
				(font
					(size 1 1)
					(thickness 0.15)
				)
			)
		)
		(property "Val" "10u"
			(at 0 0 270)
			(unlocked yes)
			(layer "F.Fab")
			(hide yes)
			(effects
				(font
					(size 1 1)
					(thickness 0.15)
				)
			)
		)
		(property "Voltage" "10V"
			(at 0 0 270)
			(unlocked yes)
			(layer "F.Fab")
			(hide yes)
			(effects
				(font
					(size 1 1)
					(thickness 0.15)
				)
			)
		)
		(property "Dielectric" "X5R"
			(at 0 0 270)
			(unlocked yes)
			(layer "F.Fab")
			(hide yes)
			(effects
				(font
					(size 1 1)
					(thickness 0.15)
				)
			)
		)
		(property "Public" ""
			(at 0 0 270)
			(unlocked yes)
			(layer "F.Fab")
			(hide yes)
			(effects
				(font
					(size 1 1)
					(thickness 0.15)
				)
			)
		)
		(sheetname "/FPGA MGT Interface/")
		(sheetfile "fpga-mgt.kicad_sch")
		(attr smd)
		(fp_rect
			(start -0.925 -0.47)
			(end 0.925 0.47)
			(stroke
				(width 0.05)
				(type default)
			)
			(fill no)
			(layer "F.CrtYd")
		)
		(fp_line
			(start -0.494 0.248)
			(end -0.494 -0.25)
			(stroke
				(width 0.15)
				(type solid)
			)
			(layer "F.Fab")
		)
		(fp_line
			(start 0.504 0.248)
			(end -0.494 0.248)
			(stroke
				(width 0.15)
				(type solid)
			)
			(layer "F.Fab")
		)
		(fp_line
			(start -0.494 -0.25)
			(end 0.504 -0.25)
			(stroke
				(width 0.15)
				(type solid)
			)
			(layer "F.Fab")
		)
		(fp_line
			(start 0.504 -0.25)
			(end 0.504 0.248)
			(stroke
				(width 0.15)
				(type solid)
			)
			(layer "F.Fab")
		)
		(fp_text user "License: Apache-2.0"
			(at -0.939 5.799 270)
			(layer "F.Fab")
			(effects
				(font
					(size 0.7 0.7)
					(thickness 0.15)
				)
				(justify left bottom)
			)
		)
		(fp_text user "${REFERENCE}"
			(at -0.939 4.599 270)
			(layer "F.Fab")
			(effects
				(font
					(size 0.7 0.7)
					(thickness 0.15)
				)
				(justify left bottom)
			)
		)
		(fp_text user "Author: Antmicro"
			(at -0.939 3.399 270)
			(layer "F.Fab")
			(effects
				(font
					(size 0.7 0.7)
					(thickness 0.15)
				)
				(justify left bottom)
			)
		)
		(pad "1" smd roundrect
			(at -0.48 0 270)
			(size 0.59 0.64)
			(layers "F.Cu" "F.Mask" "F.Paste")
			(roundrect_rratio 0.25)
			(net 1 "GND")
			(pintype "passive")
		)
		(pad "2" smd roundrect
			(at 0.48 0 270)
			(size 0.59 0.64)
			(layers "F.Cu" "F.Mask" "F.Paste")
			(roundrect_rratio 0.25)
			(net 151 "+3V3")
			(pintype "passive")
		)
	)
	(footprint "antmicro-footprints:C_0402_1005Metric"
		(layer "F.Cu")
		(at 221.29 179.18 180)
		(descr "Capacitor SMD 0402")
		(tags "capacitor SMD 0402")
		(property "Reference" "C211"
			(at 0.95 -0.42 0)
			(layer "F.SilkS")
			(effects
				(font
					(size 0.7 0.7)
					(thickness 0.15)
				)
				(justify right bottom)
			)
		)
		(property "Value" "C_1u_25V_0402"
			(at -1.022927 2.155213 0)
			(layer "F.Fab")
			(effects
				(font
					(size 0.7 0.7)
					(thickness 0.15)
				)
				(justify right bottom)
			)
		)
		(property "Datasheet" "https://www.murata.com/products/productdetail?partno=GRM155R61E105KE11%23"
			(at 0 0 180)
			(layer "F.Fab")
			(hide yes)
			(effects
				(font
					(size 1.27 1.27)
					(thickness 0.15)
				)
			)
		)
		(property "MPN" "GRM155R61E105KE11J"
			(at 0 0 180)
			(unlocked yes)
			(layer "F.Fab")
			(hide yes)
			(effects
				(font
					(size 1 1)
					(thickness 0.15)
				)
			)
		)
		(property "Manufacturer" "Murata"
			(at 0 0 180)
			(unlocked yes)
			(layer "F.Fab")
			(hide yes)
			(effects
				(font
					(size 1 1)
					(thickness 0.15)
				)
			)
		)
		(property "License" "Apache-2.0"
			(at 0 0 180)
			(unlocked yes)
			(layer "F.Fab")
			(hide yes)
			(effects
				(font
					(size 1 1)
					(thickness 0.15)
				)
			)
		)
		(property "Author" "Antmicro"
			(at 0 0 180)
			(unlocked yes)
			(layer "F.Fab")
			(hide yes)
			(effects
				(font
					(size 1 1)
					(thickness 0.15)
				)
			)
		)
		(property "Val" "1u"
			(at 0 0 180)
			(unlocked yes)
			(layer "F.Fab")
			(hide yes)
			(effects
				(font
					(size 1 1)
					(thickness 0.15)
				)
			)
		)
		(property "Voltage" "25V"
			(at 0 0 180)
			(unlocked yes)
			(layer "F.Fab")
			(hide yes)
			(effects
				(font
					(size 1 1)
					(thickness 0.15)
				)
			)
		)
		(property "Dielectric" "X5R"
			(at 0 0 180)
			(unlocked yes)
			(layer "F.Fab")
			(hide yes)
			(effects
				(font
					(size 1 1)
					(thickness 0.15)
				)
			)
		)
		(sheetname "/Supply/DC-DC VCCINT/")
		(sheetfile "dc-dc-vccint.kicad_sch")
		(attr smd)
		(fp_rect
			(start -0.925 -0.47)
			(end 0.925 0.47)
			(stroke
				(width 0.05)
				(type default)
			)
			(fill no)
			(layer "F.CrtYd")
		)
		(fp_line
			(start 0.504 0.248)
			(end -0.494 0.248)
			(stroke
				(width 0.15)
				(type solid)
			)
			(layer "F.Fab")
		)
		(fp_line
			(start 0.504 -0.25)
			(end 0.504 0.248)
			(stroke
				(width 0.15)
				(type solid)
			)
			(layer "F.Fab")
		)
		(fp_line
			(start -0.494 0.248)
			(end -0.494 -0.25)
			(stroke
				(width 0.15)
				(type solid)
			)
			(layer "F.Fab")
		)
		(fp_line
			(start -0.494 -0.25)
			(end 0.504 -0.25)
			(stroke
				(width 0.15)
				(type solid)
			)
			(layer "F.Fab")
		)
		(fp_text user "${REFERENCE}"
			(at -0.939 4.599 180)
			(layer "F.Fab")
			(effects
				(font
					(size 0.7 0.7)
					(thickness 0.15)
				)
				(justify left bottom)
			)
		)
		(fp_text user "License: Apache-2.0"
			(at -0.939 5.799 180)
			(layer "F.Fab")
			(effects
				(font
					(size 0.7 0.7)
					(thickness 0.15)
				)
				(justify left bottom)
			)
		)
		(fp_text user "Author: Antmicro"
			(at -0.939 3.399 180)
			(layer "F.Fab")
			(effects
				(font
					(size 0.7 0.7)
					(thickness 0.15)
				)
				(justify left bottom)
			)
		)
		(pad "1" smd roundrect
			(at -0.48 0 180)
			(size 0.59 0.64)
			(layers "F.Cu" "F.Mask" "F.Paste")
			(roundrect_rratio 0.25)
			(net 1 "GND")
			(pintype "passive")
		)
		(pad "2" smd roundrect
			(at 0.48 0 180)
			(size 0.59 0.64)
			(layers "F.Cu" "F.Mask" "F.Paste")
			(roundrect_rratio 0.25)
			(net 35 "VDC")
			(pintype "passive")
		)
	)
	(footprint "antmicro-footprints:R_0402_1005Metric"
		(layer "F.Cu")
		(at 114.098 112.732921 -90)
		(descr "Resistor SMD 0402")
		(tags "resistor SMD 0402")
		(property "Reference" "R16"
			(at -3.07 -0.452 90)
			(layer "F.SilkS")
			(effects
				(font
					(size 0.7 0.7)
					(thickness 0.15)
				)
				(justify right bottom)
			)
		)
		(property "Value" "R_4k7_0402"
			(at -1.011843 1.772047 90)
			(layer "F.Fab")
			(effects
				(font
					(size 0.7 0.7)
					(thickness 0.15)
				)
				(justify right bottom)
			)
		)
		(property "Datasheet" "https://www.bourns.com/docs/product-datasheets/cr.pdf"
			(at 0 0 270)
			(layer "F.Fab")
			(hide yes)
			(effects
				(font
					(size 1.27 1.27)
					(thickness 0.15)
				)
			)
		)
		(property "Manufacturer" "Bourns"
			(at 0 0 270)
			(unlocked yes)
			(layer "F.Fab")
			(hide yes)
			(effects
				(font
					(size 1 1)
					(thickness 0.15)
				)
			)
		)
		(property "MPN" "CR0402-FX-4701GLF"
			(at 0 0 270)
			(unlocked yes)
			(layer "F.Fab")
			(hide yes)
			(effects
				(font
					(size 1 1)
					(thickness 0.15)
				)
			)
		)
		(property "Val" "4k7"
			(at 0 0 270)
			(unlocked yes)
			(layer "F.Fab")
			(hide yes)
			(effects
				(font
					(size 1 1)
					(thickness 0.15)
				)
			)
		)
		(property "License" "Apache-2.0"
			(at 0 0 270)
			(unlocked yes)
			(layer "F.Fab")
			(hide yes)
			(effects
				(font
					(size 1 1)
					(thickness 0.15)
				)
			)
		)
		(property "Author" "Antmicro"
			(at 0 0 270)
			(unlocked yes)
			(layer "F.Fab")
			(hide yes)
			(effects
				(font
					(size 1 1)
					(thickness 0.15)
				)
			)
		)
		(property "Tolerance" "1%"
			(at 0 0 270)
			(unlocked yes)
			(layer "F.Fab")
			(hide yes)
			(effects
				(font
					(size 1 1)
					(thickness 0.15)
				)
			)
		)
		(sheetname "/FPGA Config/")
		(sheetfile "fpga-config.kicad_sch")
		(attr smd)
		(fp_rect
			(start -0.925 -0.47)
			(end 0.925 0.47)
			(stroke
				(width 0.05)
				(type default)
			)
			(fill no)
			(layer "F.CrtYd")
		)
		(fp_rect
			(start -0.5 -0.25)
			(end 0.5 0.25)
			(stroke
				(width 0.15)
				(type solid)
			)
			(fill no)
			(layer "F.Fab")
		)
		(fp_text user "${REFERENCE}"
			(at -0.95 3.168 270)
			(layer "F.Fab")
			(effects
				(font
					(size 0.7 0.7)
					(thickness 0.15)
				)
				(justify left bottom)
			)
		)
		(fp_text user "Author: Antmicro"
			(at -0.95 4.169 270)
			(layer "F.Fab")
			(effects
				(font
					(size 0.7 0.7)
					(thickness 0.15)
				)
				(justify left bottom)
			)
		)
		(fp_text user "License: Apache-2.0"
			(at -0.95 5.169 270)
			(layer "F.Fab")
			(effects
				(font
					(size 0.7 0.7)
					(thickness 0.15)
				)
				(justify left bottom)
			)
		)
		(pad "1" smd roundrect
			(at -0.48 0 270)
			(size 0.59 0.64)
			(layers "F.Cu" "F.Mask" "F.Paste")
			(roundrect_rratio 0.25)
			(net 797 "+1V8")
			(pintype "passive")
		)
		(pad "2" smd roundrect
			(at 0.48 0 270)
			(size 0.59 0.64)
			(layers "F.Cu" "F.Mask" "F.Paste")
			(roundrect_rratio 0.25)
			(net 341 "/FPGA Config/INIT_B")
			(pintype "passive")
		)
	)
	(footprint "antmicro-footprints:C_0402_1005Metric"
		(layer "F.Cu")
		(at 131.726 170.552 180)
		(descr "Capacitor SMD 0402")
		(tags "capacitor SMD 0402")
		(property "Reference" "C29"
			(at -0.724 0.552 0)
			(layer "F.SilkS")
			(effects
				(font
					(size 0.7 0.7)
					(thickness 0.15)
				)
				(justify right bottom)
			)
		)
		(property "Value" "C_100n_0402"
			(at -1.022927 2.155213 0)
			(layer "F.Fab")
			(effects
				(font
					(size 0.7 0.7)
					(thickness 0.15)
				)
				(justify right bottom)
			)
		)
		(property "Datasheet" "https://www.murata.com/products/productdetail?partno=GRM155R61H104KE14%23"
			(at 0 0 180)
			(layer "F.Fab")
			(hide yes)
			(effects
				(font
					(size 1.27 1.27)
					(thickness 0.15)
				)
			)
		)
		(property "MPN" "GRM155R61H104KE14D"
			(at 0 0 180)
			(unlocked yes)
			(layer "F.Fab")
			(hide yes)
			(effects
				(font
					(size 1 1)
					(thickness 0.15)
				)
			)
		)
		(property "Manufacturer" "Murata"
			(at 0 0 180)
			(unlocked yes)
			(layer "F.Fab")
			(hide yes)
			(effects
				(font
					(size 1 1)
					(thickness 0.15)
				)
			)
		)
		(property "License" "Apache-2.0"
			(at 0 0 180)
			(unlocked yes)
			(layer "F.Fab")
			(hide yes)
			(effects
				(font
					(size 1 1)
					(thickness 0.15)
				)
			)
		)
		(property "Author" "Antmicro"
			(at 0 0 180)
			(unlocked yes)
			(layer "F.Fab")
			(hide yes)
			(effects
				(font
					(size 1 1)
					(thickness 0.15)
				)
			)
		)
		(property "Val" "100n"
			(at 0 0 180)
			(unlocked yes)
			(layer "F.Fab")
			(hide yes)
			(effects
				(font
					(size 1 1)
					(thickness 0.15)
				)
			)
		)
		(property "Voltage" "50V"
			(at 0 0 180)
			(unlocked yes)
			(layer "F.Fab")
			(hide yes)
			(effects
				(font
					(size 1 1)
					(thickness 0.15)
				)
			)
		)
		(property "Dielectric" "X5R"
			(at 0 0 180)
			(unlocked yes)
			(layer "F.Fab")
			(hide yes)
			(effects
				(font
					(size 1 1)
					(thickness 0.15)
				)
			)
		)
		(property "Public" ""
			(at 0 0 180)
			(unlocked yes)
			(layer "F.Fab")
			(hide yes)
			(effects
				(font
					(size 1 1)
					(thickness 0.15)
				)
			)
		)
		(sheetname "/HDMI + SD Card/")
		(sheetfile "hdmi-sd-card.kicad_sch")
		(attr smd)
		(fp_rect
			(start -0.925 -0.47)
			(end 0.925 0.47)
			(stroke
				(width 0.05)
				(type default)
			)
			(fill no)
			(layer "F.CrtYd")
		)
		(fp_line
			(start 0.504 0.248)
			(end -0.494 0.248)
			(stroke
				(width 0.15)
				(type solid)
			)
			(layer "F.Fab")
		)
		(fp_line
			(start 0.504 -0.25)
			(end 0.504 0.248)
			(stroke
				(width 0.15)
				(type solid)
			)
			(layer "F.Fab")
		)
		(fp_line
			(start -0.494 0.248)
			(end -0.494 -0.25)
			(stroke
				(width 0.15)
				(type solid)
			)
			(layer "F.Fab")
		)
		(fp_line
			(start -0.494 -0.25)
			(end 0.504 -0.25)
			(stroke
				(width 0.15)
				(type solid)
			)
			(layer "F.Fab")
		)
		(fp_text user "${REFERENCE}"
			(at -0.939 4.599 180)
			(layer "F.Fab")
			(effects
				(font
					(size 0.7 0.7)
					(thickness 0.15)
				)
				(justify left bottom)
			)
		)
		(fp_text user "License: Apache-2.0"
			(at -0.939 5.799 180)
			(layer "F.Fab")
			(effects
				(font
					(size 0.7 0.7)
					(thickness 0.15)
				)
				(justify left bottom)
			)
		)
		(fp_text user "Author: Antmicro"
			(at -0.939 3.399 180)
			(layer "F.Fab")
			(effects
				(font
					(size 0.7 0.7)
					(thickness 0.15)
				)
				(justify left bottom)
			)
		)
		(pad "1" smd roundrect
			(at -0.48 0 180)
			(size 0.59 0.64)
			(layers "F.Cu" "F.Mask" "F.Paste")
			(roundrect_rratio 0.25)
			(net 151 "+3V3")
			(pintype "passive")
		)
		(pad "2" smd roundrect
			(at 0.48 0 180)
			(size 0.59 0.64)
			(layers "F.Cu" "F.Mask" "F.Paste")
			(roundrect_rratio 0.25)
			(net 1 "GND")
			(pintype "passive")
		)
	)
)
